# T6G (Grand Teton) — schematic netlist excerpt (pin names and nets, part order shuffled) for the footprints in the layout excerpt that follows; sources: Cadence DE-HDL packaged netlist, KiCad conversion of 04192023_DAF0TMB3IC0_F0TG_MB_C_brd_V02_OCP.brd

J30  SCONN288_DDR506112002KQ  IO  pkg DDR288S_1-1VXC  page 101
  VIN_BULK0  = P12V_MEM_CPU1
  RFU0  = NC
  VIN_MGMT  = P3V3_AUX
  HSCL  = I3C_SPD_DDRD_CPU1_SCL
  HSDA  = I3C_SPD_DDRD_CPU1_SDA
  VSS0  = GND
  DQ0_A  = M_D_CPU1_SA_DQ<0>
  VSS1  = GND
  DQ1_A  = M_D_CPU1_SA_DQ<1>
  VSS2  = GND
  DQS0_A_T  = M_D_CPU1_SA_DQS_DP<0>
  DQS0_A_C  = M_D_CPU1_SA_DQS_DN<0>
  VSS3  = GND
  DQ4_A  = M_D_CPU1_SA_DQ<4>
  VSS4  = GND
  DQ5_A  = M_D_CPU1_SA_DQ<5>
  VSS5  = GND
  DQ8_A  = M_D_CPU1_SA_DQ<8>
  VSS6  = GND
  DQ9_A  = M_D_CPU1_SA_DQ<9>
  VSS7  = GND
  DQS1_A_T  = M_D_CPU1_SA_DQS_DP<1>
  DQS1_A_C  = M_D_CPU1_SA_DQS_DN<1>
  VSS8  = GND
  DQ12_A  = M_D_CPU1_SA_DQ<12>
  VSS9  = GND
  DQ13_A  = M_D_CPU1_SA_DQ<13>
  VSS10  = GND
  DQ16_A  = M_D_CPU1_SA_DQ<16>
  VSS11  = GND
  DQ17_A  = M_D_CPU1_SA_DQ<17>
  VSS12  = GND
  DQS2_A_T  = M_D_CPU1_SA_DQS_DP<2>
  DQS2_A_C  = M_D_CPU1_SA_DQS_DN<2>
  VSS13  = GND
  DQ20_A  = M_D_CPU1_SA_DQ<20>
  VSS14  = GND
  DQ21_A  = M_D_CPU1_SA_DQ<21>
  VSS15  = GND
  DQ24_A  = M_D_CPU1_SA_DQ<24>
  VSS16  = GND
  DQ25_A  = M_D_CPU1_SA_DQ<25>
  VSS17  = GND
  DQS3_A_T  = M_D_CPU1_SA_DQS_DP<3>
  DQS3_A_C  = M_D_CPU1_SA_DQS_DN<3>
  VSS18  = GND
  DQ28_A  = M_D_CPU1_SA_DQ<28>
  VSS19  = GND
  DQ29_A  = M_D_CPU1_SA_DQ<29>
  VSS20  = GND
  CB0_A  = M_D_CPU1_SA_CB<0>
  VSS21  = GND
  CB1_A  = M_D_CPU1_SA_CB<1>
  VSS22  = GND
  DQS4_A_T  = M_D_CPU1_SA_DQS_DP<4>
  DQS4_A_C  = M_D_CPU1_SA_DQS_DN<4>
  VSS23  = GND
  CB4_A  = M_D_CPU1_SA_CB<4>
  VSS24  = GND
  CB5_A  = M_D_CPU1_SA_CB<5>
  VSS25  = GND
  ALERT_N  = M_D_CPU1_ALERT_N
  VSS26  = GND
  CS0_A_N  = M_D_CPU1_SA_CS_N<0>
  VSS27  = GND
  CA0_A  = M_D_CPU1_SA_CA<0>
  VSS28  = GND
  CA2_A  = M_D_CPU1_SA_CA<2>
  VSS29  = GND
  CA4_A  = M_D_CPU1_SA_CA<4>
  VSS30  = GND
  CA6_A  = M_D_CPU1_SA_CA<6>
  VSS31  = GND
  PAR_A  = M_D_CPU1_SA_PAR
  VSS32  = GND
  CA0_B  = M_D_CPU1_SB_CA<0>
  VSS33  = GND
  CA2_B  = M_D_CPU1_SB_CA<2>
  VSS34  = GND
  CA4_B  = M_D_CPU1_SB_CA<4>
  VSS35  = GND
  CA6_B  = M_D_CPU1_SB_CA<6>
  VSS36  = GND
  CS0_B_N  = M_D_CPU1_SB_CS_N<0>
  VSS37  = GND
  \lbd||rsp_a_n\  = M_D_CPU1_SA_RSP<0>
  \lbs||rsp_b_n\  = M_D_CPU1_SB_RSP<0>
  VSS38  = GND
  CB4_B  = M_D_CPU1_SB_CB<4>
  VSS39  = GND
  CB5_B  = M_D_CPU1_SB_CB<5>
  VSS40  = GND
  \dqs9_b_t||tdqs9_b_t||dbi4_b_n\  = M_D_CPU1_SB_DQS_DP<9>
  \dqs9_b_c||tdqs9_b_c\  = M_D_CPU1_SB_DQS_DN<9>
  VSS41  = GND
  CB0_B  = M_D_CPU1_SB_CB<0>
  VSS42  = GND
  CB1_B  = M_D_CPU1_SB_CB<1>
  VSS43  = GND
  DQ0_B  = M_D_CPU1_SB_DQ<0>
  VSS44  = GND
  DQ1_B  = M_D_CPU1_SB_DQ<1>
  VSS45  = GND
  DQS0_B_T  = M_D_CPU1_SB_DQS_DP<0>
  DQS0_B_C  = M_D_CPU1_SB_DQS_DN<0>
  VSS46  = GND
  DQ4_B  = M_D_CPU1_SB_DQ<4>
  VSS47  = GND
  DQ5_B  = M_D_CPU1_SB_DQ<5>
  VSS48  = GND
  DQ8_B  = M_D_CPU1_SB_DQ<8>
  VSS49  = GND
  DQ9_B  = M_D_CPU1_SB_DQ<9>
  VSS50  = GND
  DQS1_B_T  = M_D_CPU1_SB_DQS_DP<1>
  DQS1_B_C  = M_D_CPU1_SB_DQS_DN<1>
  VSS51  = GND
  DQ12_B  = M_D_CPU1_SB_DQ<12>
  VSS52  = GND
  DQ13_B  = M_D_CPU1_SB_DQ<13>
  VSS53  = GND
  DQ16_B  = M_D_CPU1_SB_DQ<16>
  VSS54  = GND
  DQ17_B  = M_D_CPU1_SB_DQ<17>
  VSS55  = GND
  DQS2_B_T  = M_D_CPU1_SB_DQS_DP<2>
  DQS2_B_C  = M_D_CPU1_SB_DQS_DN<2>
  VSS56  = GND
  DQ20_B  = M_D_CPU1_SB_DQ<20>
  VSS57  = GND
  DQ21_B  = M_D_CPU1_SB_DQ<21>
  VSS58  = GND
  DQ24_B  = M_D_CPU1_SB_DQ<24>
  VSS59  = GND
  DQ25_B  = M_D_CPU1_SB_DQ<25>
  VSS60  = GND
  DQS3_B_T  = M_D_CPU1_SB_DQS_DP<3>
  DQS3_B_C  = M_D_CPU1_SB_DQS_DN<3>
  VSS61  = GND
  DQ28_B  = M_D_CPU1_SB_DQ<28>
  VSS62  = GND
  DQ29_B  = M_D_CPU1_SB_DQ<29>
  VSS63  = GND
  RFU1  = NC
  VIN_BULK1  = P12V_MEM_CPU1
  VIN_BULK2  = P12V_MEM_CPU1
  \pwr_good||fail_n\  = PWRGD_CHD_CPU1_DIMM
  HAS  = PD_CHD_CPU1_DIMM_SAA
  RFU2  = NC
  RFU3  = NC
  VSS64  = GND
  DQ2_A  = M_D_CPU1_SA_DQ<2>
  VSS65  = GND
  DQ3_A  = M_D_CPU1_SA_DQ<3>
  VSS66  = GND
  \dqs5_a_c||tdqs5_a_c||dqs5_a_t||tdqs5_a_t\  = M_D_CPU1_SA_DQS_DN<5>
  \dqs5_a_t||tdqs5_a_t\  = M_D_CPU1_SA_DQS_DP<5>
  VSS67  = GND
  DQ6_A  = M_D_CPU1_SA_DQ<6>
  VSS68  = GND
  DQ7_A  = M_D_CPU1_SA_DQ<7>
  VSS69  = GND
  DQ10_A  = M_D_CPU1_SA_DQ<10>
  VSS70  = GND
  DQ11_A  = M_D_CPU1_SA_DQ<11>
  VSS71  = GND
  \dqs6_a_c||tdqs6_a_c||dqs6_a_t||tdqs6_a_t\  = M_D_CPU1_SA_DQS_DN<6>
  \dqs6_a_t||tdqs6_a_t\  = M_D_CPU1_SA_DQS_DP<6>
  VSS72  = GND
  DQ14_A  = M_D_CPU1_SA_DQ<14>
  VSS73  = GND
  DQ15_A  = M_D_CPU1_SA_DQ<15>
  VSS74  = GND
  DQ18_A  = M_D_CPU1_SA_DQ<18>
  VSS75  = GND
  DQ19_A  = M_D_CPU1_SA_DQ<19>
  VSS76  = GND
  \dqs7_a_c||tdqs7_a_c\  = M_D_CPU1_SA_DQS_DN<7>
  \dqs7_a_t||tdqs7_a_t\  = M_D_CPU1_SA_DQS_DP<7>
  VSS77  = GND
  DQ22_A  = M_D_CPU1_SA_DQ<22>
  VSS78  = GND
  DQ23_A  = M_D_CPU1_SA_DQ<23>
  VSS79  = GND
  DQ26_A  = M_D_CPU1_SA_DQ<26>
  VSS80  = GND
  DQ27_A  = M_D_CPU1_SA_DQ<27>
  VSS81  = GND
  \dqs8_a_c||tdqs8_a_c\  = M_D_CPU1_SA_DQS_DN<8>
  \dqs8_a_t||tdqs8_a_t\  = M_D_CPU1_SA_DQS_DP<8>
  VSS82  = GND
  DQ30_A  = M_D_CPU1_SA_DQ<30>
  VSS83  = GND
  DQ31_A  = M_D_CPU1_SA_DQ<31>
  VSS84  = GND
  CB2_A  = M_D_CPU1_SA_CB<2>
  VSS85  = GND
  CB3_A  = M_D_CPU1_SA_CB<3>
  VSS86  = GND
  \dqs9_a_c||tdqs9_a_c\  = M_D_CPU1_SA_DQS_DN<9>
  \dqs9_a_t||tdqs9_a_t\  = M_D_CPU1_SA_DQS_DP<9>
  VSS87  = GND
  CB6_A  = M_D_CPU1_SA_CB<6>
  VSS88  = GND
  CB7_A  = M_D_CPU1_SA_CB<7>
  VSS89  = GND
  RESET_N  = M_D_CPU1_RESET_N
  VSS90  = GND
  CS1_A_N  = M_D_CPU1_SA_CS_N<1>
  VSS91  = GND
  CA1_A  = M_D_CPU1_SA_CA<1>
  VSS92  = GND
  CA3_A  = M_D_CPU1_SA_CA<3>
  VSS93  = GND
  CA5_A  = M_D_CPU1_SA_CA<5>
  VSS94  = GND
  CK_T  = M_D_CPU1_CLK_DP<0>
  CK_C  = M_D_CPU1_CLK_DN<0>
  VSS95  = GND
  RFU4  = NC
  CA1_B  = M_D_CPU1_SB_CA<1>
  VSS96  = GND
  CA3_B  = M_D_CPU1_SB_CA<3>
  VSS97  = GND
  CA5_B  = M_D_CPU1_SB_CA<5>
  VSS98  = GND
  PAR_B  = M_D_CPU1_SB_PAR
  VSS99  = GND
  CS1_B_N  = M_D_CPU1_SB_CS_N<1>
  VSS100  = GND
  RFU5  = NC
  RFU6  = NC
  VSS101  = GND
  CB6_B  = M_D_CPU1_SB_CB<6>
  VSS102  = GND
  CB7_B  = M_D_CPU1_SB_CB<7>
  VSS103  = GND
  DQS4_B_C  = M_D_CPU1_SB_DQS_DN<4>
  DQS4_B_T  = M_D_CPU1_SB_DQS_DP<4>
  VSS104  = GND
  CB2_B  = M_D_CPU1_SB_CB<2>
  VSS105  = GND
  CB3_B  = M_D_CPU1_SB_CB<3>
  VSS106  = GND
  DQ2_B  = M_D_CPU1_SB_DQ<2>
  VSS107  = GND
  DQ3_B  = M_D_CPU1_SB_DQ<3>
  VSS108  = GND
  \dqs5_b_c||tdqs5_b_c\  = M_D_CPU1_SB_DQS_DN<5>
  \dqs5_b_t||tdqs5_b_t\  = M_D_CPU1_SB_DQS_DP<5>
  VSS109  = GND
  DQ6_B  = M_D_CPU1_SB_DQ<6>
  VSS110  = GND
  DQ7_B  = M_D_CPU1_SB_DQ<7>
  VSS111  = GND
  DQ10_B  = M_D_CPU1_SB_DQ<10>
  VSS112  = GND
  DQ11_B  = M_D_CPU1_SB_DQ<11>
  VSS113  = GND
  \dqs6_b_c||tdqs6_b_c\  = M_D_CPU1_SB_DQS_DN<6>
  \dqs6_b_t||tdqs6_b_t\  = M_D_CPU1_SB_DQS_DP<6>
  VSS114  = GND
  DQ14_B  = M_D_CPU1_SB_DQ<14>
  VSS115  = GND
  DQ15_B  = M_D_CPU1_SB_DQ<15>
  VSS116  = GND
  DQ18_B  = M_D_CPU1_SB_DQ<18>
  VSS117  = GND
  DQ19_B  = M_D_CPU1_SB_DQ<19>
  VSS118  = GND
  \dqs7_b_c||tdqs7_b_c\  = M_D_CPU1_SB_DQS_DN<7>
  \dqs7_b_t||tdqs7_b_t\  = M_D_CPU1_SB_DQS_DP<7>
  VSS119  = GND
  DQ22_B  = M_D_CPU1_SB_DQ<22>
  VSS120  = GND
  DQ23_B  = M_D_CPU1_SB_DQ<23>
  VSS121  = GND
  DQ26_B  = M_D_CPU1_SB_DQ<26>
  VSS122  = GND
  DQ27_B  = M_D_CPU1_SB_DQ<27>
  VSS123  = GND
  \dqs8_b_c||tdqs8_b_c\  = M_D_CPU1_SB_DQS_DN<8>
  \dqs8_b_t||tdqs8_b_t\  = M_D_CPU1_SB_DQS_DP<8>
  VSS124  = GND
  DQ30_B  = M_D_CPU1_SB_DQ<30>
  VSS125  = GND
  DQ31_B  = M_D_CPU1_SB_DQ<31>
  VSS126  = GND
  G1  = GND
  G2  = GND
  G3  = GND

(kicad_pcb
	(version 20260206)
	(generator "pcbnew")
	(generator_version "10.0")
	(general
		(thickness 1.6)
		(legacy_teardrops no)
	)
	(paper "A4")
	(title_block
		(title "04192023_DAF0TMB3IC0_F0TG_MB_C_brd_V02_OCP.brd")
		(comment 1 "Grand Teton / footprint 3579 of 8354 (J30), pads 277-291 of 291")
	)
	(layers
		(0 "F.Cu" signal "TOP")
		(4 "In1.Cu" signal "GND")
		(6 "In2.Cu" signal "IN1")
		(8 "In3.Cu" signal "GND1")
		(10 "In4.Cu" signal "IN2")
		(12 "In5.Cu" signal "GND2")
		(14 "In6.Cu" signal "IN3")
		(16 "In7.Cu" signal "GND3")
		(18 "In8.Cu" signal "VCC")
		(20 "In9.Cu" signal "VCC1")
		(22 "In10.Cu" signal "GND4")
		(24 "In11.Cu" signal "IN4")
		(26 "In12.Cu" signal "GND5")
		(28 "In13.Cu" signal "IN5")
		(30 "In14.Cu" signal "GND6")
		(32 "In15.Cu" signal "IN6")
		(34 "In16.Cu" signal "GND7")
		(2 "B.Cu" signal "BOTTOM")
		(9 "F.Adhes" user "F.Adhesive")
		(11 "B.Adhes" user "B.Adhesive")
		(13 "F.Paste" user "Package Geometry/Pastemask Top")
		(15 "B.Paste" user "Package Geometry/Pastemask Bottom")
		(5 "F.SilkS" user "Ref Des/Silkscreen Top")
		(7 "B.SilkS" user "Ref Des/Silkscreen Bottom")
		(1 "F.Mask" user "Board Geometry/Soldermask Top")
		(3 "B.Mask" user "Board Geometry/Soldermask Bottom")
		(17 "Dwgs.User" user "User.Drawings")
		(19 "Cmts.User" user "User.Comments")
		(21 "Eco1.User" user "User.Eco1")
		(23 "Eco2.User" user "User.Eco2")
		(25 "Edge.Cuts" user "Board Geometry/Outline")
		(27 "Margin" user)
		(31 "F.CrtYd" user "Package Geometry/Place Bound Top")
		(29 "B.CrtYd" user "Package Geometry/Place Bound Bottom")
		(35 "F.Fab" user "Ref Des/Assembly Top")
		(33 "B.Fab" user "Ref Des/Assembly Bottom")
	)
	(footprint ""
		(layer "F.Cu")
		(at 34.74593 -255.560322 180)
		(property "Reference" "J30"
			(at 3.12293 -81.850992 0)
			(unlocked yes)
			(layer "F.SilkS")
			(effects
				(font
					(size 0.7874 0.5842)
					(thickness 0.1524)
				)
			)
		)
		(property "Value" ""
			(at 0 0 180)
			(layer "F.Fab")
			(effects
				(font
					(size 1.27 1.27)
				)
			)
		)
		(duplicate_pad_numbers_are_jumpers no)
		(pad "277" smd rect
			(at 2.050034 53.975 90)
			(size 0.519938 1.4986)
			(layers "F.Cu" "F.Mask" "F.Paste")
			(net "GND")
		)
		(pad "278" smd rect
			(at 2.050034 54.824884 90)
			(size 0.519938 1.4986)
			(layers "F.Cu" "F.Mask" "F.Paste")
			(net "M_D_CPU1_SB_DQ<26>")
		)
		(pad "279" smd rect
			(at 2.050034 55.675022 90)
			(size 0.519938 1.4986)
			(layers "F.Cu" "F.Mask" "F.Paste")
			(net "GND")
		)
		(pad "280" smd rect
			(at 2.050034 56.524906 90)
			(size 0.519938 1.4986)
			(layers "F.Cu" "F.Mask" "F.Paste")
			(net "M_D_CPU1_SB_DQ<27>")
		)
		(pad "281" smd rect
			(at 2.050034 57.375044 90)
			(size 0.519938 1.4986)
			(layers "F.Cu" "F.Mask" "F.Paste")
			(net "GND")
		)
		(pad "282" smd rect
			(at 2.050034 58.224928 90)
			(size 0.519938 1.4986)
			(layers "F.Cu" "F.Mask" "F.Paste")
			(net "M_D_CPU1_SB_DQS_DN<8>")
		)
		(pad "283" smd rect
			(at 2.050034 59.075066 90)
			(size 0.519938 1.4986)
			(layers "F.Cu" "F.Mask" "F.Paste")
			(net "M_D_CPU1_SB_DQS_DP<8>")
		)
		(pad "284" smd rect
			(at 2.050034 59.92495 90)
			(size 0.519938 1.4986)
			(layers "F.Cu" "F.Mask" "F.Paste")
			(net "GND")
		)
		(pad "285" smd rect
			(at 2.050034 60.775088 90)
			(size 0.519938 1.4986)
			(layers "F.Cu" "F.Mask" "F.Paste")
			(net "M_D_CPU1_SB_DQ<30>")
		)
		(pad "286" smd rect
			(at 2.050034 61.624972 90)
			(size 0.519938 1.4986)
			(layers "F.Cu" "F.Mask" "F.Paste")
			(net "GND")
		)
		(pad "287" smd rect
			(at 2.050034 62.47511 90)
			(size 0.519938 1.4986)
			(layers "F.Cu" "F.Mask" "F.Paste")
			(net "M_D_CPU1_SB_DQ<31>")
		)
		(pad "288" smd rect
			(at 2.050034 63.324994 90)
			(size 0.519938 1.4986)
			(layers "F.Cu" "F.Mask" "F.Paste")
			(net "GND")
		)
		(pad "G1" thru_hole oval
			(at 0 -68.97497 90)
			(size 1.7272 3.4798)
			(drill oval 1.2192 2.4638)
			(layers "*.Cu" "*.Mask")
			(remove_unused_layers no)
			(net "GND")
			(clearance 0.127)
			(thermal_gap 0.127)
		)
		(pad "G2" thru_hole oval
			(at 0 3.875024 90)
			(size 1.7272 3.4798)
			(drill oval 1.2192 2.4638)
			(layers "*.Cu" "*.Mask")
			(remove_unused_layers no)
			(net "GND")
			(clearance 0.127)
			(thermal_gap 0.127)
		)
		(pad "G3" thru_hole oval
			(at 0 68.97497 90)
			(size 1.7272 3.4798)
			(drill oval 1.2192 2.4638)
			(layers "*.Cu" "*.Mask")
			(remove_unused_layers no)
			(net "GND")
			(clearance 0.127)
			(thermal_gap 0.127)
		)
	)
)
